# T6G (Grand Teton) — schematic netlist excerpt (pin names and nets, part order shuffled) for the footprints in the layout excerpt that follows; sources: Cadence DE-HDL packaged netlist, KiCad conversion of 04192023_DAF0TMB3IC0_F0TG_MB_C_brd_V02_OCP.brd

PR36  Q_RES  0 5% CHIP  pkg 0402LF  page 207 : A = NC_PVDD11_S3_P0_IMON8 ; B = GND
PR407  Q_RES  0 5% CHIP  pkg 0402LF  page 224 : A = NC_PVDD11_S3_P1_IMON4 ; B = GND

(kicad_pcb
	(version 20260206)
	(generator "pcbnew")
	(generator_version "10.0")
	(general
		(thickness 1.6)
		(legacy_teardrops no)
	)
	(paper "A4")
	(title_block
		(title "04192023_DAF0TMB3IC0_F0TG_MB_C_brd_V02_OCP.brd")
		(comment 1 "Grand Teton / footprints 2030-2031 of 8354")
	)
	(layers
		(0 "F.Cu" signal "TOP")
		(4 "In1.Cu" signal "GND")
		(6 "In2.Cu" signal "IN1")
		(8 "In3.Cu" signal "GND1")
		(10 "In4.Cu" signal "IN2")
		(12 "In5.Cu" signal "GND2")
		(14 "In6.Cu" signal "IN3")
		(16 "In7.Cu" signal "GND3")
		(18 "In8.Cu" signal "VCC")
		(20 "In9.Cu" signal "VCC1")
		(22 "In10.Cu" signal "GND4")
		(24 "In11.Cu" signal "IN4")
		(26 "In12.Cu" signal "GND5")
		(28 "In13.Cu" signal "IN5")
		(30 "In14.Cu" signal "GND6")
		(32 "In15.Cu" signal "IN6")
		(34 "In16.Cu" signal "GND7")
		(2 "B.Cu" signal "BOTTOM")
		(9 "F.Adhes" user "F.Adhesive")
		(11 "B.Adhes" user "B.Adhesive")
		(13 "F.Paste" user "Package Geometry/Pastemask Top")
		(15 "B.Paste" user "Package Geometry/Pastemask Bottom")
		(5 "F.SilkS" user "Ref Des/Silkscreen Top")
		(7 "B.SilkS" user "Ref Des/Silkscreen Bottom")
		(1 "F.Mask" user "Board Geometry/Soldermask Top")
		(3 "B.Mask" user "Board Geometry/Soldermask Bottom")
		(17 "Dwgs.User" user "User.Drawings")
		(19 "Cmts.User" user "User.Comments")
		(21 "Eco1.User" user "User.Eco1")
		(23 "Eco2.User" user "User.Eco2")
		(25 "Edge.Cuts" user "Board Geometry/Outline")
		(27 "Margin" user)
		(31 "F.CrtYd" user "Package Geometry/Place Bound Top")
		(29 "B.CrtYd" user "Package Geometry/Place Bound Bottom")
		(35 "F.Fab" user "Ref Des/Assembly Top")
		(33 "B.Fab" user "Ref Des/Assembly Bottom")
	)
	(footprint ""
		(layer "F.Cu")
		(at 163.178744 -344.153998 -90)
		(property "Reference" "PR407"
			(at 0 0 270)
			(layer "F.SilkS")
			(hide yes)
			(effects
				(font
					(size 1.27 1.27)
				)
			)
		)
		(property "Value" ""
			(at 0 0 270)
			(layer "F.Fab")
			(effects
				(font
					(size 1.27 1.27)
				)
			)
		)
		(duplicate_pad_numbers_are_jumpers no)
		(fp_line
			(start -0.7874 0.4064)
			(end -0.7874 -0.4064)
			(stroke
				(width 0.1524)
				(type default)
			)
			(layer "F.SilkS")
		)
		(fp_line
			(start 0.7874 0.4064)
			(end -0.7874 0.4064)
			(stroke
				(width 0.1524)
				(type default)
			)
			(layer "F.SilkS")
		)
		(fp_line
			(start -0.7874 -0.4064)
			(end 0.7874 -0.4064)
			(stroke
				(width 0.1524)
				(type default)
			)
			(layer "F.SilkS")
		)
		(fp_line
			(start 0.7874 -0.4064)
			(end 0.7874 0.4064)
			(stroke
				(width 0.1524)
				(type default)
			)
			(layer "F.SilkS")
		)
		(fp_line
			(start -0.67945 0.3048)
			(end -0.67945 -0.305054)
			(stroke
				(width 0.1)
				(type default)
			)
			(layer "F.Fab")
		)
		(fp_line
			(start -0.12065 0.3048)
			(end -0.67945 0.3048)
			(stroke
				(width 0.1)
				(type default)
			)
			(layer "F.Fab")
		)
		(fp_line
			(start 0.120396 0.3048)
			(end 0.120396 0.2794)
			(stroke
				(width 0.1)
				(type default)
			)
			(layer "F.Fab")
		)
		(fp_line
			(start 0.67945 0.3048)
			(end 0.120396 0.3048)
			(stroke
				(width 0.1)
				(type default)
			)
			(layer "F.Fab")
		)
		(fp_line
			(start -0.12065 0.2794)
			(end -0.12065 0.3048)
			(stroke
				(width 0.1)
				(type default)
			)
			(layer "F.Fab")
		)
		(fp_line
			(start 0.120396 0.2794)
			(end -0.12065 0.2794)
			(stroke
				(width 0.1)
				(type default)
			)
			(layer "F.Fab")
		)
		(fp_line
			(start -0.12065 -0.2794)
			(end 0.12065 -0.2794)
			(stroke
				(width 0.1)
				(type default)
			)
			(layer "F.Fab")
		)
		(fp_line
			(start 0.12065 -0.2794)
			(end 0.12065 -0.3048)
			(stroke
				(width 0.1)
				(type default)
			)
			(layer "F.Fab")
		)
		(fp_line
			(start 0.12065 -0.3048)
			(end 0.67945 -0.3048)
			(stroke
				(width 0.1)
				(type default)
			)
			(layer "F.Fab")
		)
		(fp_line
			(start 0.67945 -0.3048)
			(end 0.67945 0.3048)
			(stroke
				(width 0.1)
				(type default)
			)
			(layer "F.Fab")
		)
		(fp_line
			(start -0.67945 -0.305054)
			(end -0.12065 -0.305054)
			(stroke
				(width 0.1)
				(type default)
			)
			(layer "F.Fab")
		)
		(fp_line
			(start -0.12065 -0.305054)
			(end -0.12065 -0.2794)
			(stroke
				(width 0.1)
				(type default)
			)
			(layer "F.Fab")
		)
		(pad "1" smd circle
			(at -0.40005 0 270)
			(size 0 0)
			(layers "F.Cu" "F.Mask" "F.Paste")
			(net "NC_PVDD11_S3_P1_IMON4")
		)
		(pad "2" smd circle
			(at 0.40005 0 270)
			(size 0 0)
			(layers "F.Cu" "F.Mask" "F.Paste")
			(net "GND")
		)
	)
	(footprint ""
		(layer "F.Cu")
		(at 423.779696 -357.688134 -90)
		(property "Reference" "PR36"
			(at 0 0 270)
			(layer "F.SilkS")
			(hide yes)
			(effects
				(font
					(size 1.27 1.27)
				)
			)
		)
		(property "Value" ""
			(at 0 0 270)
			(layer "F.Fab")
			(effects
				(font
					(size 1.27 1.27)
				)
			)
		)
		(duplicate_pad_numbers_are_jumpers no)
		(fp_line
			(start -0.7874 0.4064)
			(end -0.7874 -0.4064)
			(stroke
				(width 0.1524)
				(type default)
			)
			(layer "F.SilkS")
		)
		(fp_line
			(start 0.7874 0.4064)
			(end -0.7874 0.4064)
			(stroke
				(width 0.1524)
				(type default)
			)
			(layer "F.SilkS")
		)
		(fp_line
			(start -0.7874 -0.4064)
			(end 0.7874 -0.4064)
			(stroke
				(width 0.1524)
				(type default)
			)
			(layer "F.SilkS")
		)
		(fp_line
			(start 0.7874 -0.4064)
			(end 0.7874 0.4064)
			(stroke
				(width 0.1524)
				(type default)
			)
			(layer "F.SilkS")
		)
		(fp_line
			(start -0.67945 0.3048)
			(end -0.67945 -0.305054)
			(stroke
				(width 0.1)
				(type default)
			)
			(layer "F.Fab")
		)
		(fp_line
			(start -0.12065 0.3048)
			(end -0.67945 0.3048)
			(stroke
				(width 0.1)
				(type default)
			)
			(layer "F.Fab")
		)
		(fp_line
			(start 0.120396 0.3048)
			(end 0.120396 0.2794)
			(stroke
				(width 0.1)
				(type default)
			)
			(layer "F.Fab")
		)
		(fp_line
			(start 0.67945 0.3048)
			(end 0.120396 0.3048)
			(stroke
				(width 0.1)
				(type default)
			)
			(layer "F.Fab")
		)
		(fp_line
			(start -0.12065 0.2794)
			(end -0.12065 0.3048)
			(stroke
				(width 0.1)
				(type default)
			)
			(layer "F.Fab")
		)
		(fp_line
			(start 0.120396 0.2794)
			(end -0.12065 0.2794)
			(stroke
				(width 0.1)
				(type default)
			)
			(layer "F.Fab")
		)
		(fp_line
			(start -0.12065 -0.2794)
			(end 0.12065 -0.2794)
			(stroke
				(width 0.1)
				(type default)
			)
			(layer "F.Fab")
		)
		(fp_line
			(start 0.12065 -0.2794)
			(end 0.12065 -0.3048)
			(stroke
				(width 0.1)
				(type default)
			)
			(layer "F.Fab")
		)
		(fp_line
			(start 0.12065 -0.3048)
			(end 0.67945 -0.3048)
			(stroke
				(width 0.1)
				(type default)
			)
			(layer "F.Fab")
		)
		(fp_line
			(start 0.67945 -0.3048)
			(end 0.67945 0.3048)
			(stroke
				(width 0.1)
				(type default)
			)
			(layer "F.Fab")
		)
		(fp_line
			(start -0.67945 -0.305054)
			(end -0.12065 -0.305054)
			(stroke
				(width 0.1)
				(type default)
			)
			(layer "F.Fab")
		)
		(fp_line
			(start -0.12065 -0.305054)
			(end -0.12065 -0.2794)
			(stroke
				(width 0.1)
				(type default)
			)
			(layer "F.Fab")
		)
		(pad "1" smd circle
			(at -0.40005 0 270)
			(size 0 0)
			(layers "F.Cu" "F.Mask" "F.Paste")
			(net "NC_PVDD11_S3_P0_IMON8")
		)
		(pad "2" smd circle
			(at 0.40005 0 270)
			(size 0 0)
			(layers "F.Cu" "F.Mask" "F.Paste")
			(net "GND")
		)
	)
)
